# T6G (Grand Teton) — schematic netlist excerpt (pin names and nets, part order shuffled) for the footprints in the layout excerpt that follows; sources: Cadence DE-HDL packaged netlist, KiCad conversion of 04192023_DAF0TMB3IC0_F0TG_MB_C_brd_V02_OCP.brd

R198  Q_RES  0 5% CHIP  pkg 0402LF  page 81 : A = RST_CPU1_PERST1_N ; B = RST_CPU1_PERST1_R_N
R564  Q_RES  0 5% CHIP  pkg 0402LF  page 159 : A = I3C_0_SPD_DDRAF_CPU1_SCL ; B = I3C_0_SPD_DDRAF_CPU1_R_SCL

(kicad_pcb
	(version 20260206)
	(generator "pcbnew")
	(generator_version "10.0")
	(general
		(thickness 1.6)
		(legacy_teardrops no)
	)
	(paper "A4")
	(title_block
		(title "04192023_DAF0TMB3IC0_F0TG_MB_C_brd_V02_OCP.brd")
		(comment 1 "Grand Teton / footprints 714-715 of 8354")
	)
	(layers
		(0 "F.Cu" signal "TOP")
		(4 "In1.Cu" signal "GND")
		(6 "In2.Cu" signal "IN1")
		(8 "In3.Cu" signal "GND1")
		(10 "In4.Cu" signal "IN2")
		(12 "In5.Cu" signal "GND2")
		(14 "In6.Cu" signal "IN3")
		(16 "In7.Cu" signal "GND3")
		(18 "In8.Cu" signal "VCC")
		(20 "In9.Cu" signal "VCC1")
		(22 "In10.Cu" signal "GND4")
		(24 "In11.Cu" signal "IN4")
		(26 "In12.Cu" signal "GND5")
		(28 "In13.Cu" signal "IN5")
		(30 "In14.Cu" signal "GND6")
		(32 "In15.Cu" signal "IN6")
		(34 "In16.Cu" signal "GND7")
		(2 "B.Cu" signal "BOTTOM")
		(9 "F.Adhes" user "F.Adhesive")
		(11 "B.Adhes" user "B.Adhesive")
		(13 "F.Paste" user "Package Geometry/Pastemask Top")
		(15 "B.Paste" user "Package Geometry/Pastemask Bottom")
		(5 "F.SilkS" user "Ref Des/Silkscreen Top")
		(7 "B.SilkS" user "Ref Des/Silkscreen Bottom")
		(1 "F.Mask" user "Board Geometry/Soldermask Top")
		(3 "B.Mask" user "Board Geometry/Soldermask Bottom")
		(17 "Dwgs.User" user "User.Drawings")
		(19 "Cmts.User" user "User.Comments")
		(21 "Eco1.User" user "User.Eco1")
		(23 "Eco2.User" user "User.Eco2")
		(25 "Edge.Cuts" user "Board Geometry/Outline")
		(27 "Margin" user)
		(31 "F.CrtYd" user "Package Geometry/Place Bound Top")
		(29 "B.CrtYd" user "Package Geometry/Place Bound Bottom")
		(35 "F.Fab" user "Ref Des/Assembly Top")
		(33 "B.Fab" user "Ref Des/Assembly Bottom")
	)
	(footprint ""
		(layer "F.Cu")
		(at 178.943 -137.632948 -90)
		(property "Reference" "R198"
			(at 0 0 270)
			(layer "F.SilkS")
			(hide yes)
			(effects
				(font
					(size 1.27 1.27)
				)
			)
		)
		(property "Value" ""
			(at 0 0 270)
			(layer "F.Fab")
			(effects
				(font
					(size 1.27 1.27)
				)
			)
		)
		(duplicate_pad_numbers_are_jumpers no)
		(fp_line
			(start -0.7874 0.4064)
			(end -0.7874 -0.4064)
			(stroke
				(width 0.1524)
				(type default)
			)
			(layer "F.SilkS")
		)
		(fp_line
			(start 0.7874 0.4064)
			(end -0.7874 0.4064)
			(stroke
				(width 0.1524)
				(type default)
			)
			(layer "F.SilkS")
		)
		(fp_line
			(start -0.7874 -0.4064)
			(end 0.7874 -0.4064)
			(stroke
				(width 0.1524)
				(type default)
			)
			(layer "F.SilkS")
		)
		(fp_line
			(start 0.7874 -0.4064)
			(end 0.7874 0.4064)
			(stroke
				(width 0.1524)
				(type default)
			)
			(layer "F.SilkS")
		)
		(fp_line
			(start -0.67945 0.3048)
			(end -0.67945 -0.305054)
			(stroke
				(width 0.1)
				(type default)
			)
			(layer "F.Fab")
		)
		(fp_line
			(start -0.12065 0.3048)
			(end -0.67945 0.3048)
			(stroke
				(width 0.1)
				(type default)
			)
			(layer "F.Fab")
		)
		(fp_line
			(start 0.120396 0.3048)
			(end 0.120396 0.2794)
			(stroke
				(width 0.1)
				(type default)
			)
			(layer "F.Fab")
		)
		(fp_line
			(start 0.67945 0.3048)
			(end 0.120396 0.3048)
			(stroke
				(width 0.1)
				(type default)
			)
			(layer "F.Fab")
		)
		(fp_line
			(start -0.12065 0.2794)
			(end -0.12065 0.3048)
			(stroke
				(width 0.1)
				(type default)
			)
			(layer "F.Fab")
		)
		(fp_line
			(start 0.120396 0.2794)
			(end -0.12065 0.2794)
			(stroke
				(width 0.1)
				(type default)
			)
			(layer "F.Fab")
		)
		(fp_line
			(start -0.12065 -0.2794)
			(end 0.12065 -0.2794)
			(stroke
				(width 0.1)
				(type default)
			)
			(layer "F.Fab")
		)
		(fp_line
			(start 0.12065 -0.2794)
			(end 0.12065 -0.3048)
			(stroke
				(width 0.1)
				(type default)
			)
			(layer "F.Fab")
		)
		(fp_line
			(start 0.12065 -0.3048)
			(end 0.67945 -0.3048)
			(stroke
				(width 0.1)
				(type default)
			)
			(layer "F.Fab")
		)
		(fp_line
			(start 0.67945 -0.3048)
			(end 0.67945 0.3048)
			(stroke
				(width 0.1)
				(type default)
			)
			(layer "F.Fab")
		)
		(fp_line
			(start -0.67945 -0.305054)
			(end -0.12065 -0.305054)
			(stroke
				(width 0.1)
				(type default)
			)
			(layer "F.Fab")
		)
		(fp_line
			(start -0.12065 -0.305054)
			(end -0.12065 -0.2794)
			(stroke
				(width 0.1)
				(type default)
			)
			(layer "F.Fab")
		)
		(pad "1" smd circle
			(at -0.40005 0 270)
			(size 0 0)
			(layers "F.Cu" "F.Mask" "F.Paste")
			(net "RST_CPU1_PERST1_N")
		)
		(pad "2" smd circle
			(at 0.40005 0 270)
			(size 0 0)
			(layers "F.Cu" "F.Mask" "F.Paste")
			(net "RST_CPU1_PERST1_R_N")
		)
	)
	(footprint ""
		(layer "F.Cu")
		(at 42.672 -170.307)
		(property "Reference" "R564"
			(at 0 0 0)
			(layer "F.SilkS")
			(hide yes)
			(effects
				(font
					(size 1.27 1.27)
				)
			)
		)
		(property "Value" ""
			(at 0 0 0)
			(layer "F.Fab")
			(effects
				(font
					(size 1.27 1.27)
				)
			)
		)
		(duplicate_pad_numbers_are_jumpers no)
		(fp_line
			(start -0.7874 -0.4064)
			(end 0.7874 -0.4064)
			(stroke
				(width 0.1524)
				(type default)
			)
			(layer "F.SilkS")
		)
		(fp_line
			(start -0.7874 0.4064)
			(end -0.7874 -0.4064)
			(stroke
				(width 0.1524)
				(type default)
			)
			(layer "F.SilkS")
		)
		(fp_line
			(start 0.7874 -0.4064)
			(end 0.7874 0.4064)
			(stroke
				(width 0.1524)
				(type default)
			)
			(layer "F.SilkS")
		)
		(fp_line
			(start 0.7874 0.4064)
			(end -0.7874 0.4064)
			(stroke
				(width 0.1524)
				(type default)
			)
			(layer "F.SilkS")
		)
		(fp_line
			(start -0.67945 -0.305054)
			(end -0.12065 -0.305054)
			(stroke
				(width 0.1)
				(type default)
			)
			(layer "F.Fab")
		)
		(fp_line
			(start -0.67945 0.3048)
			(end -0.67945 -0.305054)
			(stroke
				(width 0.1)
				(type default)
			)
			(layer "F.Fab")
		)
		(fp_line
			(start -0.12065 -0.305054)
			(end -0.12065 -0.2794)
			(stroke
				(width 0.1)
				(type default)
			)
			(layer "F.Fab")
		)
		(fp_line
			(start -0.12065 -0.2794)
			(end 0.12065 -0.2794)
			(stroke
				(width 0.1)
				(type default)
			)
			(layer "F.Fab")
		)
		(fp_line
			(start -0.12065 0.2794)
			(end -0.12065 0.3048)
			(stroke
				(width 0.1)
				(type default)
			)
			(layer "F.Fab")
		)
		(fp_line
			(start -0.12065 0.3048)
			(end -0.67945 0.3048)
			(stroke
				(width 0.1)
				(type default)
			)
			(layer "F.Fab")
		)
		(fp_line
			(start 0.120396 0.2794)
			(end -0.12065 0.2794)
			(stroke
				(width 0.1)
				(type default)
			)
			(layer "F.Fab")
		)
		(fp_line
			(start 0.120396 0.3048)
			(end 0.120396 0.2794)
			(stroke
				(width 0.1)
				(type default)
			)
			(layer "F.Fab")
		)
		(fp_line
			(start 0.12065 -0.3048)
			(end 0.67945 -0.3048)
			(stroke
				(width 0.1)
				(type default)
			)
			(layer "F.Fab")
		)
		(fp_line
			(start 0.12065 -0.2794)
			(end 0.12065 -0.3048)
			(stroke
				(width 0.1)
				(type default)
			)
			(layer "F.Fab")
		)
		(fp_line
			(start 0.67945 -0.3048)
			(end 0.67945 0.3048)
			(stroke
				(width 0.1)
				(type default)
			)
			(layer "F.Fab")
		)
		(fp_line
			(start 0.67945 0.3048)
			(end 0.120396 0.3048)
			(stroke
				(width 0.1)
				(type default)
			)
			(layer "F.Fab")
		)
		(pad "1" smd rect
			(at -0.40005 0 180)
			(size 0.4572 0.508)
			(layers "F.Cu" "F.Mask" "F.Paste")
			(net "I3C_0_SPD_DDRAF_CPU1_SCL")
		)
		(pad "2" smd rect
			(at 0.40005 0 180)
			(size 0.4572 0.508)
			(layers "F.Cu" "F.Mask" "F.Paste")
			(net "I3C_0_SPD_DDRAF_CPU1_R_SCL")
		)
	)
)
